(kicad_pcb
	(version 20241229)
	(generator "pcbnew")
	(generator_version "9.0")
	(general
		(thickness 1.61)
		(legacy_teardrops no)
	)
	(paper "A3")
	(title_block
		(title "SO-DIMM DDR5 Tester")
		(date "2025-11-26")
		(rev "1.3.0")
		(comment 9 "footprints 196-199 of 627")
	)
	(layers
		(0 "F.Cu" signal)
		(4 "In1.Cu" power)
		(6 "In2.Cu" mixed)
		(8 "In3.Cu" power)
		(10 "In4.Cu" mixed)
		(12 "In5.Cu" power)
		(14 "In6.Cu" mixed)
		(16 "In7.Cu" power)
		(18 "In8.Cu" power)
		(20 "In9.Cu" mixed)
		(22 "In10.Cu" power)
		(2 "B.Cu" signal)
		(9 "F.Adhes" user "F.Adhesive")
		(11 "B.Adhes" user "B.Adhesive")
		(13 "F.Paste" user)
		(15 "B.Paste" user)
		(5 "F.SilkS" user "F.Silkscreen")
		(7 "B.SilkS" user "B.Silkscreen")
		(1 "F.Mask" user)
		(3 "B.Mask" user)
		(17 "Dwgs.User" user "User.Drawings")
		(19 "Cmts.User" user "User.Comments")
		(21 "Eco1.User" user "User.Eco1")
		(23 "Eco2.User" user "User.Eco2")
		(25 "Edge.Cuts" user)
		(27 "Margin" user)
		(31 "F.CrtYd" user "F.Courtyard")
		(29 "B.CrtYd" user "B.Courtyard")
		(35 "F.Fab" user)
		(33 "B.Fab" user)
	)
	(footprint "antmicro-footprints:USON-10_2.5x1mm_P0.5mm"
		(layer "F.Cu")
		(at 77.7 155.3 180)
		(descr "USON-10 2.5x1mm_ Pitch 0.5mm")
		(tags "USON-10 2.5x1mm Pitch 0.5mm")
		(property "Reference" "U8"
			(at 0.018 -1.7 180)
			(layer "F.SilkS")
			(hide yes)
			(effects
				(font
					(size 0.7 0.7)
					(thickness 0.15)
				)
				(justify left bottom)
			)
		)
		(property "Value" "TPD4E05U06QDQARQ1"
			(at 0.018 2.499 180)
			(layer "F.Fab")
			(effects
				(font
					(size 0.7 0.7)
					(thickness 0.15)
				)
				(justify left bottom)
			)
		)
		(property "Datasheet" "https://www.ti.com/lit/ds/symlink/tpd4e05u06-q1.pdf?HQS=dis-mous-null-mousermode-dsf-pf-null-wwe&ts=1663591265741&ref_url=https%253A%252F%252Fwww.mouser.com%252F"
			(at 0 0 180)
			(layer "F.Fab")
			(hide yes)
			(effects
				(font
					(size 1.27 1.27)
					(thickness 0.15)
				)
			)
		)
		(property "Author" "Antmicro"
			(at 155.4 310.6 0)
			(layer "F.Fab")
			(hide yes)
			(effects
				(font
					(size 1 1)
					(thickness 0.15)
				)
			)
		)
		(property "License" "Apache-2.0"
			(at 155.4 310.6 0)
			(layer "F.Fab")
			(hide yes)
			(effects
				(font
					(size 1 1)
					(thickness 0.15)
				)
			)
		)
		(property "MPN" "TPD4E05U06QDQARQ1"
			(at 155.4 310.6 0)
			(layer "F.Fab")
			(hide yes)
			(effects
				(font
					(size 1 1)
					(thickness 0.15)
				)
			)
		)
		(property "Manufacturer" "Texas Instruments"
			(at 155.4 310.6 0)
			(layer "F.Fab")
			(hide yes)
			(effects
				(font
					(size 1 1)
					(thickness 0.15)
				)
			)
		)
		(sheetname "/Debug FTDI/")
		(sheetfile "debug-ftdi.kicad_sch")
		(attr smd)
		(fp_line
			(start 0.498 1.398)
			(end -0.5 1.398)
			(stroke
				(width 0.15)
				(type solid)
			)
			(layer "F.SilkS")
		)
		(fp_line
			(start 0.498 -1.401)
			(end -0.5 -1.401)
			(stroke
				(width 0.15)
				(type solid)
			)
			(layer "F.SilkS")
		)
		(fp_circle
			(center -0.68 -1.27)
			(end -0.63 -1.27)
			(stroke
				(width 0.15)
				(type solid)
			)
			(fill yes)
			(layer "F.SilkS")
		)
		(fp_rect
			(start -0.8 -1.5)
			(end 0.8 1.499)
			(stroke
				(width 0.05)
				(type solid)
			)
			(fill no)
			(layer "F.CrtYd")
		)
		(fp_line
			(start 0.498 -1.25)
			(end 0.498 1.249)
			(stroke
				(width 0.15)
				(type solid)
			)
			(layer "F.Fab")
		)
		(fp_line
			(start 0.498 -1.25)
			(end -0.25 -1.25)
			(stroke
				(width 0.15)
				(type solid)
			)
			(layer "F.Fab")
		)
		(fp_line
			(start -0.25 -1.25)
			(end -0.5 -1)
			(stroke
				(width 0.15)
				(type solid)
			)
			(layer "F.Fab")
		)
		(fp_line
			(start -0.5 1.249)
			(end 0.498 1.249)
			(stroke
				(width 0.15)
				(type solid)
			)
			(layer "F.Fab")
		)
		(fp_line
			(start -0.5 -1)
			(end -0.5 1.249)
			(stroke
				(width 0.15)
				(type solid)
			)
			(layer "F.Fab")
		)
		(pad "1" smd roundrect
			(at -0.387 -1 90)
			(size 0.25 0.55)
			(layers "F.Cu" "F.Mask" "F.Paste")
			(roundrect_rratio 0.25)
			(net 571 "unconnected-(U8-Pad1)")
			(pintype "passive+no_connect")
		)
		(pad "2" smd roundrect
			(at -0.387 -0.5 90)
			(size 0.25 0.55)
			(layers "F.Cu" "F.Mask" "F.Paste")
			(roundrect_rratio 0.25)
			(net 290 "/Debug FTDI/DBG_USB_P")
			(pintype "passive")
		)
		(pad "3" smd roundrect
			(at -0.387 0 90)
			(size 0.4 0.55)
			(layers "F.Cu" "F.Mask" "F.Paste")
			(roundrect_rratio 0.25)
			(net 1 "GND")
			(pintype "power_in")
		)
		(pad "4" smd roundrect
			(at -0.387 0.498 90)
			(size 0.25 0.55)
			(layers "F.Cu" "F.Mask" "F.Paste")
			(roundrect_rratio 0.25)
			(net 291 "/Debug FTDI/DBG_USB_N")
			(pintype "passive")
		)
		(pad "5" smd roundrect
			(at -0.387 0.998 90)
			(size 0.25 0.55)
			(layers "F.Cu" "F.Mask" "F.Paste")
			(roundrect_rratio 0.25)
			(net 753 "unconnected-(U8-Pad5)_1")
			(pintype "passive+no_connect")
		)
		(pad "6" smd roundrect
			(at 0.385 0.998 90)
			(size 0.25 0.55)
			(layers "F.Cu" "F.Mask" "F.Paste")
			(roundrect_rratio 0.25)
			(net 572 "unconnected-(U8-Pad5)")
			(pintype "passive+no_connect")
		)
		(pad "7" smd roundrect
			(at 0.385 0.498 90)
			(size 0.25 0.55)
			(layers "F.Cu" "F.Mask" "F.Paste")
			(roundrect_rratio 0.25)
			(net 291 "/Debug FTDI/DBG_USB_N")
			(pintype "passive")
		)
		(pad "8" smd roundrect
			(at 0.385 0 90)
			(size 0.4 0.55)
			(layers "F.Cu" "F.Mask" "F.Paste")
			(roundrect_rratio 0.25)
			(net 1 "GND")
			(pintype "passive")
		)
		(pad "9" smd roundrect
			(at 0.385 -0.5 90)
			(size 0.25 0.55)
			(layers "F.Cu" "F.Mask" "F.Paste")
			(roundrect_rratio 0.25)
			(net 290 "/Debug FTDI/DBG_USB_P")
			(pintype "passive")
		)
		(pad "10" smd roundrect
			(at 0.385 -1 90)
			(size 0.25 0.55)
			(layers "F.Cu" "F.Mask" "F.Paste")
			(roundrect_rratio 0.25)
			(net 754 "unconnected-(U8-Pad1)_1")
			(pintype "passive+no_connect")
		)
	)
	(footprint "antmicro-footprints:SW_KMR211NGLFS_SMD"
		(layer "F.Cu")
		(at 202.95 144.8 90)
		(property "Reference" "SW2"
			(at -1.1 -2 90)
			(layer "F.SilkS")
			(effects
				(font
					(size 0.7 0.7)
					(thickness 0.15)
				)
				(justify left bottom)
			)
		)
		(property "Value" "SW_KMR211NGLFS_SMD"
			(at 0 2.8 90)
			(layer "F.Fab")
			(effects
				(font
					(size 0.7 0.7)
					(thickness 0.15)
				)
				(justify left bottom)
			)
		)
		(property "Datasheet" "http://www.farnell.com/datasheets/2631211.pdf"
			(at 0 0 90)
			(layer "F.Fab")
			(hide yes)
			(effects
				(font
					(size 1.27 1.27)
					(thickness 0.15)
				)
			)
		)
		(property "Author" "Antmicro"
			(at 347.75 -58.15 0)
			(layer "F.Fab")
			(hide yes)
			(effects
				(font
					(size 1 1)
					(thickness 0.15)
				)
			)
		)
		(property "License" "Apache-2.0"
			(at 347.75 -58.15 0)
			(layer "F.Fab")
			(hide yes)
			(effects
				(font
					(size 1 1)
					(thickness 0.15)
				)
			)
		)
		(property "MPN" "KMR211NGLFS"
			(at 347.75 -58.15 0)
			(layer "F.Fab")
			(hide yes)
			(effects
				(font
					(size 1 1)
					(thickness 0.15)
				)
			)
		)
		(property "Manufacturer" "C&K"
			(at 347.75 -58.15 0)
			(layer "F.Fab")
			(hide yes)
			(effects
				(font
					(size 1 1)
					(thickness 0.15)
				)
			)
		)
		(sheetname "/FPGA Config/")
		(sheetfile "fpga-config.kicad_sch")
		(attr smd)
		(fp_line
			(start 2.101 -1.6)
			(end -2.1 -1.6)
			(stroke
				(width 0.15)
				(type solid)
			)
			(layer "F.SilkS")
		)
		(fp_line
			(start -2.1 -1.6)
			(end -2.1 -1.499)
			(stroke
				(width 0.15)
				(type solid)
			)
			(layer "F.SilkS")
		)
		(fp_line
			(start 2.101 -1.58)
			(end 2.101 -1.459)
			(stroke
				(width 0.15)
				(type solid)
			)
			(layer "F.SilkS")
		)
		(fp_line
			(start 2.101 1.601)
			(end 2.101 1.48)
			(stroke
				(width 0.15)
				(type solid)
			)
			(layer "F.SilkS")
		)
		(fp_line
			(start 2.101 1.601)
			(end -2.1 1.601)
			(stroke
				(width 0.15)
				(type solid)
			)
			(layer "F.SilkS")
		)
		(fp_line
			(start -2.1 1.601)
			(end -2.1 1.48)
			(stroke
				(width 0.15)
				(type solid)
			)
			(layer "F.SilkS")
		)
		(fp_rect
			(start 2.751 1.75)
			(end -2.748 -1.749)
			(stroke
				(width 0.05)
				(type solid)
			)
			(fill no)
			(layer "F.CrtYd")
		)
		(fp_line
			(start 2.101 -1.6)
			(end -2.1 -1.6)
			(stroke
				(width 0.15)
				(type solid)
			)
			(layer "F.Fab")
		)
		(fp_line
			(start -2.1 -1.6)
			(end -2.1 1.601)
			(stroke
				(width 0.15)
				(type solid)
			)
			(layer "F.Fab")
		)
		(fp_line
			(start -0.248 -0.8)
			(end 0.25 -0.8)
			(stroke
				(width 0.15)
				(type solid)
			)
			(layer "F.Fab")
		)
		(fp_line
			(start 0.25 0.802)
			(end -0.248 0.802)
			(stroke
				(width 0.15)
				(type solid)
			)
			(layer "F.Fab")
		)
		(fp_line
			(start 2.101 1.601)
			(end 2.101 -1.6)
			(stroke
				(width 0.15)
				(type solid)
			)
			(layer "F.Fab")
		)
		(fp_line
			(start -2.1 1.601)
			(end 2.101 1.601)
			(stroke
				(width 0.15)
				(type solid)
			)
			(layer "F.Fab")
		)
		(fp_arc
			(start 0.25 -0.8)
			(mid 1.051001 0.001)
			(end 0.25 0.802)
			(stroke
				(width 0.15)
				(type solid)
			)
			(layer "F.Fab")
		)
		(fp_arc
			(start -0.248 0.802)
			(mid -1.050001 0.001)
			(end -0.248 -0.8)
			(stroke
				(width 0.15)
				(type solid)
			)
			(layer "F.Fab")
		)
		(pad "1" smd rect
			(at -2.048 -0.8 270)
			(size 0.9 1)
			(layers "F.Cu" "F.Mask" "F.Paste")
			(net 634 "/FPGA Config/PROGRAM_B")
			(pinfunction "1")
			(pintype "passive")
		)
		(pad "2" smd rect
			(at 2.05 -0.8 270)
			(size 0.9 1)
			(layers "F.Cu" "F.Mask" "F.Paste")
			(net 634 "/FPGA Config/PROGRAM_B")
			(pinfunction "2")
			(pintype "passive")
		)
		(pad "3" smd rect
			(at -2.048 0.802 270)
			(size 0.9 1)
			(layers "F.Cu" "F.Mask" "F.Paste")
			(net 1 "GND")
			(pinfunction "3")
			(pintype "passive")
		)
		(pad "4" smd rect
			(at 2.05 0.802 270)
			(size 0.9 1)
			(layers "F.Cu" "F.Mask" "F.Paste")
			(net 1 "GND")
			(pinfunction "4")
			(pintype "passive")
		)
	)
	(footprint "antmicro-footprints:TP_SMD_1mm"
		(layer "F.Cu")
		(at 186.4 164.5845)
		(property "Reference" "TP12"
			(at 0 -0.731898 0)
			(layer "F.SilkS")
			(hide yes)
			(effects
				(font
					(size 0.7 0.7)
					(thickness 0.15)
				)
				(justify left bottom)
			)
		)
		(property "Value" "TP_1mm_SMD"
			(at 0 1.4 0)
			(layer "F.Fab")
			(effects
				(font
					(size 0.7 0.7)
					(thickness 0.15)
				)
				(justify left bottom)
			)
		)
		(property "Author" "Antmicro"
			(at 0 0 0)
			(layer "F.Fab")
			(hide yes)
			(effects
				(font
					(size 1 1)
					(thickness 0.15)
				)
			)
		)
		(property "License" "Apache-2.0"
			(at 0 0 0)
			(layer "F.Fab")
			(hide yes)
			(effects
				(font
					(size 1 1)
					(thickness 0.15)
				)
			)
		)
		(property "MPN" ""
			(at 0 0 0)
			(layer "F.Fab")
			(hide yes)
			(effects
				(font
					(size 1 1)
					(thickness 0.15)
				)
			)
		)
		(property "Manufacturer" ""
			(at 0 0 0)
			(layer "F.Fab")
			(hide yes)
			(effects
				(font
					(size 1 1)
					(thickness 0.15)
				)
			)
		)
		(sheetname "/Supply/")
		(sheetfile "supply.kicad_sch")
		(attr exclude_from_pos_files)
		(pad "1" smd circle
			(at 0 0)
			(size 1 1)
			(layers "F.Cu" "F.Mask")
			(net 201 "+5V")
			(pinfunction "1")
			(pintype "passive")
		)
	)
	(footprint "antmicro-footprints:USON-10_2.5x1mm_P0.5mm"
		(layer "F.Cu")
		(at 82.4 194.1 180)
		(descr "USON-10 2.5x1mm_ Pitch 0.5mm")
		(tags "USON-10 2.5x1mm Pitch 0.5mm")
		(property "Reference" "U10"
			(at 0.018 -1.7 180)
			(layer "F.SilkS")
			(hide yes)
			(effects
				(font
					(size 0.7 0.7)
					(thickness 0.15)
				)
				(justify left bottom)
			)
		)
		(property "Value" "TPD4E05U06QDQARQ1"
			(at 0.018 2.499 180)
			(layer "F.Fab")
			(effects
				(font
					(size 0.7 0.7)
					(thickness 0.15)
				)
				(justify left bottom)
			)
		)
		(property "Datasheet" "https://www.ti.com/lit/ds/symlink/tpd4e05u06-q1.pdf?HQS=dis-mous-null-mousermode-dsf-pf-null-wwe&ts=1663591265741&ref_url=https%253A%252F%252Fwww.mouser.com%252F"
			(at 0 0 180)
			(layer "F.Fab")
			(hide yes)
			(effects
				(font
					(size 1.27 1.27)
					(thickness 0.15)
				)
			)
		)
		(property "Author" "Antmicro"
			(at 164.8 388.2 0)
			(layer "F.Fab")
			(hide yes)
			(effects
				(font
					(size 1 1)
					(thickness 0.15)
				)
			)
		)
		(property "License" "Apache-2.0"
			(at 164.8 388.2 0)
			(layer "F.Fab")
			(hide yes)
			(effects
				(font
					(size 1 1)
					(thickness 0.15)
				)
			)
		)
		(property "MPN" "TPD4E05U06QDQARQ1"
			(at 164.8 388.2 0)
			(layer "F.Fab")
			(hide yes)
			(effects
				(font
					(size 1 1)
					(thickness 0.15)
				)
			)
		)
		(property "Manufacturer" "Texas Instruments"
			(at 164.8 388.2 0)
			(layer "F.Fab")
			(hide yes)
			(effects
				(font
					(size 1 1)
					(thickness 0.15)
				)
			)
		)
		(sheetname "/HDMI + SD Card/")
		(sheetfile "hdmi-sd-card.kicad_sch")
		(attr smd)
		(fp_line
			(start 0.498 1.398)
			(end -0.5 1.398)
			(stroke
				(width 0.15)
				(type solid)
			)
			(layer "F.SilkS")
		)
		(fp_line
			(start 0.498 -1.401)
			(end -0.5 -1.401)
			(stroke
				(width 0.15)
				(type solid)
			)
			(layer "F.SilkS")
		)
		(fp_circle
			(center -0.68 -1.27)
			(end -0.63 -1.27)
			(stroke
				(width 0.15)
				(type solid)
			)
			(fill yes)
			(layer "F.SilkS")
		)
		(fp_rect
			(start -0.8 -1.5)
			(end 0.8 1.499)
			(stroke
				(width 0.05)
				(type solid)
			)
			(fill no)
			(layer "F.CrtYd")
		)
		(fp_line
			(start 0.498 -1.25)
			(end 0.498 1.249)
			(stroke
				(width 0.15)
				(type solid)
			)
			(layer "F.Fab")
		)
		(fp_line
			(start 0.498 -1.25)
			(end -0.25 -1.25)
			(stroke
				(width 0.15)
				(type solid)
			)
			(layer "F.Fab")
		)
		(fp_line
			(start -0.25 -1.25)
			(end -0.5 -1)
			(stroke
				(width 0.15)
				(type solid)
			)
			(layer "F.Fab")
		)
		(fp_line
			(start -0.5 1.249)
			(end 0.498 1.249)
			(stroke
				(width 0.15)
				(type solid)
			)
			(layer "F.Fab")
		)
		(fp_line
			(start -0.5 -1)
			(end -0.5 1.249)
			(stroke
				(width 0.15)
				(type solid)
			)
			(layer "F.Fab")
		)
		(pad "1" smd roundrect
			(at -0.387 -1 90)
			(size 0.25 0.55)
			(layers "F.Cu" "F.Mask" "F.Paste")
			(roundrect_rratio 0.25)
			(net 292 "/HDMI + SD Card/HDMI_CONN_D2_P")
			(pintype "passive")
		)
		(pad "2" smd roundrect
			(at -0.387 -0.5 90)
			(size 0.25 0.55)
			(layers "F.Cu" "F.Mask" "F.Paste")
			(roundrect_rratio 0.25)
			(net 293 "/HDMI + SD Card/HDMI_CONN_D2_N")
			(pintype "passive")
		)
		(pad "3" smd roundrect
			(at -0.387 0 90)
			(size 0.4 0.55)
			(layers "F.Cu" "F.Mask" "F.Paste")
			(roundrect_rratio 0.25)
			(net 1 "GND")
			(pintype "power_in")
		)
		(pad "4" smd roundrect
			(at -0.387 0.498 90)
			(size 0.25 0.55)
			(layers "F.Cu" "F.Mask" "F.Paste")
			(roundrect_rratio 0.25)
			(net 294 "/HDMI + SD Card/HDMI_CONN_D1_P")
			(pintype "passive")
		)
		(pad "5" smd roundrect
			(at -0.387 0.998 90)
			(size 0.25 0.55)
			(layers "F.Cu" "F.Mask" "F.Paste")
			(roundrect_rratio 0.25)
			(net 295 "/HDMI + SD Card/HDMI_CONN_D1_N")
			(pintype "passive")
		)
		(pad "6" smd roundrect
			(at 0.385 0.998 90)
			(size 0.25 0.55)
			(layers "F.Cu" "F.Mask" "F.Paste")
			(roundrect_rratio 0.25)
			(net 295 "/HDMI + SD Card/HDMI_CONN_D1_N")
			(pintype "passive")
		)
		(pad "7" smd roundrect
			(at 0.385 0.498 90)
			(size 0.25 0.55)
			(layers "F.Cu" "F.Mask" "F.Paste")
			(roundrect_rratio 0.25)
			(net 294 "/HDMI + SD Card/HDMI_CONN_D1_P")
			(pintype "passive")
		)
		(pad "8" smd roundrect
			(at 0.385 0 90)
			(size 0.4 0.55)
			(layers "F.Cu" "F.Mask" "F.Paste")
			(roundrect_rratio 0.25)
			(net 1 "GND")
			(pintype "passive")
		)
		(pad "9" smd roundrect
			(at 0.385 -0.5 90)
			(size 0.25 0.55)
			(layers "F.Cu" "F.Mask" "F.Paste")
			(roundrect_rratio 0.25)
			(net 293 "/HDMI + SD Card/HDMI_CONN_D2_N")
			(pintype "passive")
		)
		(pad "10" smd roundrect
			(at 0.385 -1 90)
			(size 0.25 0.55)
			(layers "F.Cu" "F.Mask" "F.Paste")
			(roundrect_rratio 0.25)
			(net 292 "/HDMI + SD Card/HDMI_CONN_D2_P")
			(pintype "passive")
		)
	)
)
